# T6G (Grand Teton) — schematic netlist excerpt (pin names and nets, part order shuffled) for the footprints in the layout excerpt that follows; sources: Cadence DE-HDL packaged netlist, KiCad conversion of 04192023_DAF0TMB3IC0_F0TG_MB_C_brd_V02_OCP.brd

C192  Q_CAP  0.1UF 10V 10% X7S  pkg C0201  page 323 : A = P0V9_CPU1_RT0_2A ; B = GND
C1804  Q_CAP  0.1UF 25V 10% X7R  pkg 0402  page 127 : A = FM_SMB_2_ALERT_GPU_ISO_N ; B = GND
PR6819  Q_RES  0 5% CHIP  pkg 0402LF  page 362 : A = P0V9_RETIMER_CPU0_SVID_SDA ; B = GND

(kicad_pcb
	(version 20260206)
	(generator "pcbnew")
	(generator_version "10.0")
	(general
		(thickness 1.6)
		(legacy_teardrops no)
	)
	(paper "A4")
	(title_block
		(title "04192023_DAF0TMB3IC0_F0TG_MB_C_brd_V02_OCP.brd")
		(comment 1 "Grand Teton / footprints 6476-6478 of 8354")
	)
	(layers
		(0 "F.Cu" signal "TOP")
		(4 "In1.Cu" signal "GND")
		(6 "In2.Cu" signal "IN1")
		(8 "In3.Cu" signal "GND1")
		(10 "In4.Cu" signal "IN2")
		(12 "In5.Cu" signal "GND2")
		(14 "In6.Cu" signal "IN3")
		(16 "In7.Cu" signal "GND3")
		(18 "In8.Cu" signal "VCC")
		(20 "In9.Cu" signal "VCC1")
		(22 "In10.Cu" signal "GND4")
		(24 "In11.Cu" signal "IN4")
		(26 "In12.Cu" signal "GND5")
		(28 "In13.Cu" signal "IN5")
		(30 "In14.Cu" signal "GND6")
		(32 "In15.Cu" signal "IN6")
		(34 "In16.Cu" signal "GND7")
		(2 "B.Cu" signal "BOTTOM")
		(9 "F.Adhes" user "F.Adhesive")
		(11 "B.Adhes" user "B.Adhesive")
		(13 "F.Paste" user "Package Geometry/Pastemask Top")
		(15 "B.Paste" user "Package Geometry/Pastemask Bottom")
		(5 "F.SilkS" user "Ref Des/Silkscreen Top")
		(7 "B.SilkS" user "Ref Des/Silkscreen Bottom")
		(1 "F.Mask" user "Board Geometry/Soldermask Top")
		(3 "B.Mask" user "Board Geometry/Soldermask Bottom")
		(17 "Dwgs.User" user "User.Drawings")
		(19 "Cmts.User" user "User.Comments")
		(21 "Eco1.User" user "User.Eco1")
		(23 "Eco2.User" user "User.Eco2")
		(25 "Edge.Cuts" user "Board Geometry/Outline")
		(27 "Margin" user)
		(31 "F.CrtYd" user "Package Geometry/Place Bound Top")
		(29 "B.CrtYd" user "Package Geometry/Place Bound Bottom")
		(35 "F.Fab" user "Ref Des/Assembly Top")
		(33 "B.Fab" user "Ref Des/Assembly Bottom")
	)
	(footprint ""
		(layer "B.Cu")
		(at 64.318642 -388.011162 -90)
		(property "Reference" "C192"
			(at 0 0 90)
			(layer "B.SilkS")
			(hide yes)
			(effects
				(font
					(size 1.27 1.27)
				)
				(justify mirror)
			)
		)
		(property "Value" ""
			(at 0 0 90)
			(layer "B.Fab")
			(effects
				(font
					(size 1.27 1.27)
				)
				(justify mirror)
			)
		)
		(duplicate_pad_numbers_are_jumpers no)
		(fp_line
			(start -0.299974 0.150114)
			(end 0.299974 0.150114)
			(stroke
				(width 0.1)
				(type default)
			)
			(layer "B.Fab")
		)
		(fp_line
			(start 0.299974 0.150114)
			(end 0.299974 -0.150114)
			(stroke
				(width 0.1)
				(type default)
			)
			(layer "B.Fab")
		)
		(fp_line
			(start -0.299974 -0.150114)
			(end -0.299974 0.150114)
			(stroke
				(width 0.1)
				(type default)
			)
			(layer "B.Fab")
		)
		(fp_line
			(start 0.299974 -0.150114)
			(end -0.299974 -0.150114)
			(stroke
				(width 0.1)
				(type default)
			)
			(layer "B.Fab")
		)
		(pad "1" smd rect
			(at 0.2667 0 90)
			(size 0.3048 0.381)
			(layers "B.Cu" "B.Mask" "B.Paste")
			(net "P0V9_CPU1_RT0_2A")
		)
		(pad "2" smd rect
			(at -0.2667 0 90)
			(size 0.3048 0.381)
			(layers "B.Cu" "B.Mask" "B.Paste")
			(net "GND")
		)
	)
	(footprint ""
		(layer "B.Cu")
		(at 108.712 -417.83 90)
		(property "Reference" "C1804"
			(at 0 0 90)
			(layer "B.SilkS")
			(hide yes)
			(effects
				(font
					(size 1.27 1.27)
				)
				(justify mirror)
			)
		)
		(property "Value" ""
			(at 0 0 90)
			(layer "B.Fab")
			(effects
				(font
					(size 1.27 1.27)
				)
				(justify mirror)
			)
		)
		(duplicate_pad_numbers_are_jumpers no)
		(fp_line
			(start 0.7874 -0.4064)
			(end -0.7874 -0.4064)
			(stroke
				(width 0.1524)
				(type default)
			)
			(layer "B.SilkS")
		)
		(fp_line
			(start -0.7874 -0.4064)
			(end -0.7874 0.4064)
			(stroke
				(width 0.1524)
				(type default)
			)
			(layer "B.SilkS")
		)
		(fp_line
			(start 0.7874 0.4064)
			(end 0.7874 -0.4064)
			(stroke
				(width 0.1524)
				(type default)
			)
			(layer "B.SilkS")
		)
		(fp_line
			(start -0.7874 0.4064)
			(end 0.7874 0.4064)
			(stroke
				(width 0.1524)
				(type default)
			)
			(layer "B.SilkS")
		)
		(fp_line
			(start 0.67945 -0.305054)
			(end 0.12065 -0.305054)
			(stroke
				(width 0.1)
				(type default)
			)
			(layer "B.Fab")
		)
		(fp_line
			(start 0.12065 -0.305054)
			(end 0.12065 -0.2794)
			(stroke
				(width 0.1)
				(type default)
			)
			(layer "B.Fab")
		)
		(fp_line
			(start -0.12065 -0.3048)
			(end -0.67945 -0.3048)
			(stroke
				(width 0.1)
				(type default)
			)
			(layer "B.Fab")
		)
		(fp_line
			(start -0.67945 -0.3048)
			(end -0.67945 0.3048)
			(stroke
				(width 0.1)
				(type default)
			)
			(layer "B.Fab")
		)
		(fp_line
			(start 0.12065 -0.2794)
			(end -0.12065 -0.2794)
			(stroke
				(width 0.1)
				(type default)
			)
			(layer "B.Fab")
		)
		(fp_line
			(start -0.12065 -0.2794)
			(end -0.12065 -0.3048)
			(stroke
				(width 0.1)
				(type default)
			)
			(layer "B.Fab")
		)
		(fp_line
			(start 0.12065 0.2794)
			(end 0.12065 0.3048)
			(stroke
				(width 0.1)
				(type default)
			)
			(layer "B.Fab")
		)
		(fp_line
			(start -0.120396 0.2794)
			(end 0.12065 0.2794)
			(stroke
				(width 0.1)
				(type default)
			)
			(layer "B.Fab")
		)
		(fp_line
			(start 0.67945 0.3048)
			(end 0.67945 -0.305054)
			(stroke
				(width 0.1)
				(type default)
			)
			(layer "B.Fab")
		)
		(fp_line
			(start 0.12065 0.3048)
			(end 0.67945 0.3048)
			(stroke
				(width 0.1)
				(type default)
			)
			(layer "B.Fab")
		)
		(fp_line
			(start -0.120396 0.3048)
			(end -0.120396 0.2794)
			(stroke
				(width 0.1)
				(type default)
			)
			(layer "B.Fab")
		)
		(fp_line
			(start -0.67945 0.3048)
			(end -0.120396 0.3048)
			(stroke
				(width 0.1)
				(type default)
			)
			(layer "B.Fab")
		)
		(pad "1" smd circle
			(at 0.40005 0 270)
			(size 0 0)
			(layers "B.Cu" "B.Mask" "B.Paste")
			(net "FM_SMB_2_ALERT_GPU_ISO_N")
		)
		(pad "2" smd circle
			(at -0.40005 0 270)
			(size 0 0)
			(layers "B.Cu" "B.Mask" "B.Paste")
			(net "GND")
		)
	)
	(footprint ""
		(layer "B.Cu")
		(at 439.029602 -422.52011)
		(property "Reference" "PR6819"
			(at 0 0 0)
			(layer "B.SilkS")
			(hide yes)
			(effects
				(font
					(size 1.27 1.27)
				)
				(justify mirror)
			)
		)
		(property "Value" ""
			(at 0 0 0)
			(layer "B.Fab")
			(effects
				(font
					(size 1.27 1.27)
				)
				(justify mirror)
			)
		)
		(duplicate_pad_numbers_are_jumpers no)
		(fp_line
			(start -0.7874 -0.4064)
			(end -0.7874 0.4064)
			(stroke
				(width 0.1524)
				(type default)
			)
			(layer "B.SilkS")
		)
		(fp_line
			(start -0.7874 0.4064)
			(end 0.7874 0.4064)
			(stroke
				(width 0.1524)
				(type default)
			)
			(layer "B.SilkS")
		)
		(fp_line
			(start 0.7874 -0.4064)
			(end -0.7874 -0.4064)
			(stroke
				(width 0.1524)
				(type default)
			)
			(layer "B.SilkS")
		)
		(fp_line
			(start 0.7874 0.4064)
			(end 0.7874 -0.4064)
			(stroke
				(width 0.1524)
				(type default)
			)
			(layer "B.SilkS")
		)
		(fp_line
			(start -0.67945 -0.3048)
			(end -0.67945 0.3048)
			(stroke
				(width 0.1)
				(type default)
			)
			(layer "B.Fab")
		)
		(fp_line
			(start -0.67945 0.3048)
			(end -0.120396 0.3048)
			(stroke
				(width 0.1)
				(type default)
			)
			(layer "B.Fab")
		)
		(fp_line
			(start -0.12065 -0.3048)
			(end -0.67945 -0.3048)
			(stroke
				(width 0.1)
				(type default)
			)
			(layer "B.Fab")
		)
		(fp_line
			(start -0.12065 -0.2794)
			(end -0.12065 -0.3048)
			(stroke
				(width 0.1)
				(type default)
			)
			(layer "B.Fab")
		)
		(fp_line
			(start -0.120396 0.2794)
			(end 0.12065 0.2794)
			(stroke
				(width 0.1)
				(type default)
			)
			(layer "B.Fab")
		)
		(fp_line
			(start -0.120396 0.3048)
			(end -0.120396 0.2794)
			(stroke
				(width 0.1)
				(type default)
			)
			(layer "B.Fab")
		)
		(fp_line
			(start 0.12065 -0.305054)
			(end 0.12065 -0.2794)
			(stroke
				(width 0.1)
				(type default)
			)
			(layer "B.Fab")
		)
		(fp_line
			(start 0.12065 -0.2794)
			(end -0.12065 -0.2794)
			(stroke
				(width 0.1)
				(type default)
			)
			(layer "B.Fab")
		)
		(fp_line
			(start 0.12065 0.2794)
			(end 0.12065 0.3048)
			(stroke
				(width 0.1)
				(type default)
			)
			(layer "B.Fab")
		)
		(fp_line
			(start 0.12065 0.3048)
			(end 0.67945 0.3048)
			(stroke
				(width 0.1)
				(type default)
			)
			(layer "B.Fab")
		)
		(fp_line
			(start 0.67945 -0.305054)
			(end 0.12065 -0.305054)
			(stroke
				(width 0.1)
				(type default)
			)
			(layer "B.Fab")
		)
		(fp_line
			(start 0.67945 0.3048)
			(end 0.67945 -0.305054)
			(stroke
				(width 0.1)
				(type default)
			)
			(layer "B.Fab")
		)
		(pad "1" smd circle
			(at 0.40005 0 180)
			(size 0 0)
			(layers "B.Cu" "B.Mask" "B.Paste")
			(net "P0V9_RETIMER_CPU0_SVID_SDA")
		)
		(pad "2" smd circle
			(at -0.40005 0 180)
			(size 0 0)
			(layers "B.Cu" "B.Mask" "B.Paste")
			(net "GND")
		)
	)
)
